#ISCELL
  logical_power cad_note *
  *
#ISCELL
  mstr_misc dns *
  *
#ISCELL
  pure_quanta quanta_title_block_c *
  *
#ISCELL
  standard offpage *
  page131_i1
#ISCELL
  logical_power gnd *
  page131_i10
#CELL
  pure_quanta q_cap *
  page131_i100
#ISCELL
  logical_power gnd *
  page131_i101
#CELL
  pure_quanta q_cap *
  page131_i102
#ISCELL
  logical_power universal_power *
  page131_i103
#ISCELL
  logical_power gnd *
  page131_i104
#CELL
  pure_quanta q_cap *
  page131_i105
#CELL
  pure_quanta q_res *
  page131_i106
#CELL
  pure_quanta schottky_ac *
  page131_i107
#CELL
  pure_quanta q_res *
  page131_i108
#CELL
  pure_quanta q_cap *
  page131_i109
#CELL
  pure_quanta q_res *
  page131_i11
#CELL
  pure_quanta q_res *
  page131_i110
#ISCELL
  logical_power vccaux15 *
  page131_i111
#ISCELL
  logical_power gnd *
  page131_i112
#CELL
  pure_quanta q_cap *
  page131_i113
#ISCELL
  logical_power universal_power *
  page131_i114
#ISCELL
  standard offpage *
  page131_i115
#ISCELL
  logical_power universal_power *
  page131_i12
#CELL
  pure_quanta q_res *
  page131_i13
#CELL
  pure_quanta q_res *
  page131_i14
#ISCELL
  logical_power universal_power *
  page131_i15
#CELL
  pure_quanta mosfet_nch_dual *
  page131_i16
#ISCELL
  logical_power gnd *
  page131_i17
#ISCELL
  logical_power universal_gnd *
  page131_i18
#CELL
  pure_quanta 74lvc2g07dw7 *
  page131_i19
#ISCELL
  standard offpage *
  page131_i2
#ISCELL
  logical_power universal_gnd *
  page131_i20
#CELL
  pure_quanta q_cap *
  page131_i21
#ISCELL
  logical_power universal_power *
  page131_i22
#ISCELL
  logical_power universal_gnd *
  page131_i23
#ISCELL
  logical_power universal_gnd *
  page131_i24
#CELL
  pure_quanta 74lvc2g07dw7 *
  page131_i25
#CELL
  pure_quanta q_cap *
  page131_i26
#ISCELL
  logical_power universal_power *
  page131_i27
#ISCELL
  logical_power gnd *
  page131_i28
#CELL
  pure_quanta q_res *
  page131_i29
#CELL
  pure_quanta q_res *
  page131_i3
#CELL
  pure_quanta q_res *
  page131_i30
#ISCELL
  logical_power gnd *
  page131_i31
#CELL
  pure_quanta q_res *
  page131_i32
#CELL
  pure_quanta q_res *
  page131_i33
#ISCELL
  standard offpage *
  page131_i34
#CELL
  pure_quanta q_res *
  page131_i35
#ISCELL
  logical_power gnd *
  page131_i36
#CELL
  pure_quanta q_res *
  page131_i37
#CELL
  pure_quanta mosfet_nch_dual *
  page131_i38
#ISCELL
  logical_power gnd *
  page131_i39
#ISCELL
  logical_power universal_power *
  page131_i4
#CELL
  pure_quanta q_res *
  page131_i40
#ISCELL
  logical_power universal_power *
  page131_i41
#CELL
  pure_quanta mosfet_nch_dual *
  page131_i42
#ISCELL
  logical_power gnd *
  page131_i43
#CELL
  pure_quanta diode_tvs *
  page131_i44
#ISCELL
  logical_power universal_power *
  page131_i45
#CELL
  pure_quanta q_cap *
  page131_i46
#CELL
  pure_quanta q_res *
  page131_i47
#CELL
  pure_quanta q_res *
  page131_i48
#ISCELL
  logical_power gnd *
  page131_i49
#CELL
  pure_quanta q_res *
  page131_i5
#CELL
  pure_quanta q_res *
  page131_i50
#ISCELL
  logical_power gnd *
  page131_i51
#CELL
  pure_quanta q_cap *
  page131_i52
#CELL
  pure_quanta q_res *
  page131_i53
#ISCELL
  logical_power universal_power *
  page131_i54
#CELL
  pure_quanta q_res *
  page131_i55
#CELL
  pure_quanta q_res *
  page131_i56
#CELL
  pure_quanta q_res *
  page131_i57
#ISCELL
  logical_power gnd *
  page131_i58
#CELL
  pure_quanta q_res *
  page131_i59
#CELL
  pure_quanta q_res *
  page131_i6
#ISCELL
  logical_power gnd *
  page131_i60
#CELL
  pure_quanta q_cap *
  page131_i61
#CELL
  pure_quanta q_cap *
  page131_i62
#CELL
  pure_quanta max15090bewit *
  page131_i63
#CELL
  pure_quanta q_res *
  page131_i64
#ISCELL
  logical_power universal_power *
  page131_i65
#CELL
  pure_quanta q_res *
  page131_i66
#ISCELL
  standard offpage *
  page131_i67
#ISCELL
  standard offpage *
  page131_i68
#ISCELL
  standard offpage *
  page131_i69
#CELL
  pure_quanta mosfet_nch_dual *
  page131_i7
#CELL
  pure_quanta q_res *
  page131_i70
#ISCELL
  logical_power gnd *
  page131_i71
#CELL
  pure_quanta q_res *
  page131_i72
#CELL
  pure_quanta q_cap *
  page131_i73
#CELL
  pure_quanta q_res *
  page131_i74
#CELL
  pure_quanta q_res *
  page131_i75
#CELL
  pure_quanta q_cap *
  page131_i76
#CELL
  pure_quanta q_res *
  page131_i77
#CELL
  pure_quanta q_res *
  page131_i78
#ISCELL
  logical_power gnd *
  page131_i79
#ISCELL
  standard offpage *
  page131_i8
#CELL
  pure_quanta q_res *
  page131_i80
#CELL
  pure_quanta q_res *
  page131_i81
#ISCELL
  standard offpage *
  page131_i82
#ISCELL
  standard offpage *
  page131_i83
#ISCELL
  standard offpage *
  page131_i84
#CELL
  pure_quanta q_res *
  page131_i85
#ISCELL
  logical_power gnd *
  page131_i86
#CELL
  pure_quanta q_cap *
  page131_i87
#ISCELL
  logical_power gnd *
  page131_i88
#CELL
  pure_quanta q_res *
  page131_i89
#ISCELL
  standard offpage *
  page131_i9
#CELL
  pure_quanta max15090bewit *
  page131_i90
#CELL
  pure_quanta q_cap *
  page131_i91
#CELL
  pure_quanta q_res *
  page131_i92
#CELL
  pure_quanta schottky_ac *
  page131_i93
#ISCELL
  logical_power gnd *
  page131_i94
#CELL
  pure_quanta q_res *
  page131_i95
#CELL
  pure_quanta q_cap *
  page131_i96
#CELL
  pure_quanta q_res *
  page131_i97
#CELL
  pure_quanta q_cap *
  page131_i98
#ISCELL
  logical_power vccaux15 *
  page131_i99
